(kicad_pcb
	(version 20260206)
	(generator "pcbnew")
	(generator_version "10.0")
	(general
		(thickness 1.6)
		(legacy_teardrops no)
	)
	(paper "A4")
	(title_block
		(title "9054_F0T_PDB_BD_GPU_F_V04_1213_1550_OCP.brd")
		(comment 1 "Grand Teton / footprints 543-545 of 608")
	)
	(layers
		(0 "F.Cu" signal "TOP")
		(4 "In1.Cu" signal "GND")
		(6 "In2.Cu" signal "IN1")
		(8 "In3.Cu" signal "GND1")
		(10 "In4.Cu" signal "VCC")
		(12 "In5.Cu" signal "VCC1")
		(14 "In6.Cu" signal "GND2")
		(16 "In7.Cu" signal "IN2")
		(18 "In8.Cu" signal "GND3")
		(2 "B.Cu" signal "BOTTOM")
		(9 "F.Adhes" user "F.Adhesive")
		(11 "B.Adhes" user "B.Adhesive")
		(13 "F.Paste" user "Package Geometry/Pastemask Top")
		(15 "B.Paste" user "Package Geometry/Pastemask Bottom")
		(5 "F.SilkS" user "Ref Des/Silkscreen Top")
		(7 "B.SilkS" user "Ref Des/Silkscreen Bottom")
		(1 "F.Mask" user "Board Geometry/Soldermask Top")
		(3 "B.Mask" user "Board Geometry/Soldermask Bottom")
		(17 "Dwgs.User" user "User.Drawings")
		(19 "Cmts.User" user "User.Comments")
		(21 "Eco1.User" user "User.Eco1")
		(23 "Eco2.User" user "User.Eco2")
		(25 "Edge.Cuts" user "Board Geometry/Outline")
		(27 "Margin" user)
		(31 "F.CrtYd" user "Package Geometry/Place Bound Top")
		(29 "B.CrtYd" user "Package Geometry/Place Bound Bottom")
		(35 "F.Fab" user "Ref Des/Assembly Top")
		(33 "B.Fab" user "Ref Des/Assembly Bottom")
	)
	(footprint ""
		(layer "B.Cu")
		(at 277.9014 -70.612 180)
		(property "Reference" "PC591"
			(at 0 0 0)
			(layer "B.SilkS")
			(hide yes)
			(effects
				(font
					(size 1.27 1.27)
				)
				(justify mirror)
			)
		)
		(property "Value" ""
			(at 0 0 0)
			(layer "B.Fab")
			(effects
				(font
					(size 1.27 1.27)
				)
				(justify mirror)
			)
		)
		(duplicate_pad_numbers_are_jumpers no)
		(fp_line
			(start 1.2954 0.5842)
			(end 1.2954 -0.5842)
			(stroke
				(width 0.1524)
				(type default)
			)
			(layer "B.SilkS")
		)
		(fp_line
			(start 1.2954 -0.5842)
			(end -1.2954 -0.5842)
			(stroke
				(width 0.1524)
				(type default)
			)
			(layer "B.SilkS")
		)
		(fp_line
			(start -1.2954 0.5842)
			(end 1.2954 0.5842)
			(stroke
				(width 0.1524)
				(type default)
			)
			(layer "B.SilkS")
		)
		(fp_line
			(start -1.2954 -0.5842)
			(end -1.2954 0.5842)
			(stroke
				(width 0.1524)
				(type default)
			)
			(layer "B.SilkS")
		)
		(fp_line
			(start 1.1938 0.4064)
			(end 1.1938 -0.4064)
			(stroke
				(width 0.1)
				(type default)
			)
			(layer "B.Fab")
		)
		(fp_line
			(start 1.1938 -0.4064)
			(end 0.8636 -0.4064)
			(stroke
				(width 0.1)
				(type default)
			)
			(layer "B.Fab")
		)
		(fp_line
			(start 0.8636 0.4572)
			(end 0.8636 0.4064)
			(stroke
				(width 0.1)
				(type default)
			)
			(layer "B.Fab")
		)
		(fp_line
			(start 0.8636 0.4064)
			(end 1.1938 0.4064)
			(stroke
				(width 0.1)
				(type default)
			)
			(layer "B.Fab")
		)
		(fp_line
			(start 0.8636 -0.4064)
			(end 0.8636 -0.4572)
			(stroke
				(width 0.1)
				(type default)
			)
			(layer "B.Fab")
		)
		(fp_line
			(start 0.8636 -0.4572)
			(end -0.8636 -0.4572)
			(stroke
				(width 0.1)
				(type default)
			)
			(layer "B.Fab")
		)
		(fp_line
			(start -0.8636 0.4572)
			(end 0.8636 0.4572)
			(stroke
				(width 0.1)
				(type default)
			)
			(layer "B.Fab")
		)
		(fp_line
			(start -0.8636 0.4064)
			(end -0.8636 0.4572)
			(stroke
				(width 0.1)
				(type default)
			)
			(layer "B.Fab")
		)
		(fp_line
			(start -0.8636 -0.4064)
			(end -1.1938 -0.4064)
			(stroke
				(width 0.1)
				(type default)
			)
			(layer "B.Fab")
		)
		(fp_line
			(start -0.8636 -0.4572)
			(end -0.8636 -0.4064)
			(stroke
				(width 0.1)
				(type default)
			)
			(layer "B.Fab")
		)
		(fp_line
			(start -1.1938 0.4064)
			(end -0.8636 0.4064)
			(stroke
				(width 0.1)
				(type default)
			)
			(layer "B.Fab")
		)
		(fp_line
			(start -1.1938 -0.4064)
			(end -1.1938 0.4064)
			(stroke
				(width 0.1)
				(type default)
			)
			(layer "B.Fab")
		)
		(pad "1" smd rect
			(at 0.7366 0 90)
			(size 0.7112 0.8128)
			(layers "B.Cu" "B.Mask" "B.Paste")
			(net "P52V_HS1_VCAP")
		)
		(pad "2" smd rect
			(at -0.7366 0 90)
			(size 0.7112 0.8128)
			(layers "B.Cu" "B.Mask" "B.Paste")
			(net "GND_FIELD_SIGNAL")
		)
	)
	(footprint ""
		(layer "B.Cu")
		(at 293.5224 -70.104)
		(property "Reference" "PU1"
			(at 6.1976 -5.05333 0)
			(unlocked yes)
			(layer "B.SilkS")
			(effects
				(font
					(size 0.7874 0.5842)
					(thickness 0.1524)
				)
				(justify left mirror)
			)
		)
		(property "Value" ""
			(at 0 0 0)
			(layer "B.Fab")
			(effects
				(font
					(size 1.27 1.27)
				)
				(justify mirror)
			)
		)
		(duplicate_pad_numbers_are_jumpers no)
		(fp_line
			(start -3.549904 -3.549904)
			(end -3.549904 -3.0226)
			(stroke
				(width 0.1524)
				(type default)
			)
			(layer "B.SilkS")
		)
		(fp_line
			(start -3.549904 3.0226)
			(end -3.549904 3.549904)
			(stroke
				(width 0.1524)
				(type default)
			)
			(layer "B.SilkS")
		)
		(fp_line
			(start -3.549904 3.549904)
			(end -3.0226 3.549904)
			(stroke
				(width 0.1524)
				(type default)
			)
			(layer "B.SilkS")
		)
		(fp_line
			(start -3.0226 -3.549904)
			(end -3.549904 -3.549904)
			(stroke
				(width 0.1524)
				(type default)
			)
			(layer "B.SilkS")
		)
		(fp_line
			(start 1.03124 3.549904)
			(end 2.4638 3.549904)
			(stroke
				(width 0.1524)
				(type default)
			)
			(layer "B.SilkS")
		)
		(fp_line
			(start 2.4638 -3.549904)
			(end 1.03124 -3.549904)
			(stroke
				(width 0.1524)
				(type default)
			)
			(layer "B.SilkS")
		)
		(fp_line
			(start 3.0226 3.549904)
			(end 3.549904 3.549904)
			(stroke
				(width 0.1524)
				(type default)
			)
			(layer "B.SilkS")
		)
		(fp_line
			(start 3.549904 -3.549904)
			(end 3.0226 -3.549904)
			(stroke
				(width 0.1524)
				(type default)
			)
			(layer "B.SilkS")
		)
		(fp_line
			(start 3.549904 -3.0226)
			(end 3.549904 -3.549904)
			(stroke
				(width 0.1524)
				(type default)
			)
			(layer "B.SilkS")
		)
		(fp_line
			(start 3.549904 -0.0254)
			(end 3.549904 -1.4732)
			(stroke
				(width 0.1524)
				(type default)
			)
			(layer "B.SilkS")
		)
		(fp_line
			(start 3.549904 3.549904)
			(end 3.549904 3.0226)
			(stroke
				(width 0.1524)
				(type default)
			)
			(layer "B.SilkS")
		)
		(fp_poly
			(pts
				(xy 4.134104 -3.041904) (xy 3.549904 -3.041904) (xy 3.549904 -3.626104) (xy 4.134104 -3.626104)
			)
			(stroke
				(width 0)
				(type default)
			)
			(fill yes)
			(layer "B.SilkS")
		)
		(fp_line
			(start -3.549904 -3.549904)
			(end -3.549904 3.549904)
			(stroke
				(width 0.1)
				(type default)
			)
			(layer "B.Fab")
		)
		(fp_line
			(start -3.549904 3.549904)
			(end 3.549904 3.549904)
			(stroke
				(width 0.1)
				(type default)
			)
			(layer "B.Fab")
		)
		(fp_line
			(start 3.549904 -3.549904)
			(end -3.549904 -3.549904)
			(stroke
				(width 0.1)
				(type default)
			)
			(layer "B.Fab")
		)
		(fp_line
			(start 3.549904 3.549904)
			(end 3.549904 -3.549904)
			(stroke
				(width 0.1)
				(type default)
			)
			(layer "B.Fab")
		)
		(fp_poly
			(pts
				(xy 4.134104 -3.041904) (xy 3.549904 -3.041904) (xy 3.549904 -3.626104) (xy 4.134104 -3.626104)
			)
			(stroke
				(width 0)
				(type default)
			)
			(fill yes)
			(layer "B.Fab")
		)
		(pad "1" smd rect
			(at 3.425444 -2.750058 270)
			(size 0.2794 0.7112)
			(layers "B.Cu" "B.Mask" "B.Paste")
			(net "P52V_HS1")
		)
		(pad "2" smd rect
			(at 3.400044 -2.249932 270)
			(size 0.2794 0.762)
			(layers "B.Cu" "B.Mask" "B.Paste")
			(net "P52V_HS1_4287_GATE2_R")
		)
		(pad "3" smd rect
			(at 3.400044 -1.75006 270)
			(size 0.2794 0.762)
			(layers "B.Cu" "B.Mask" "B.Paste")
			(net "P52V_HS1_4287_GATE_R")
		)
		(pad "4" smd rect
			(at 3.400044 0.249936 270)
			(size 0.2794 0.762)
			(layers "B.Cu" "B.Mask" "B.Paste")
			(net "P52V_HS_4287_ADC_N")
		)
		(pad "5" smd rect
			(at 3.400044 0.750062 270)
			(size 0.2794 0.762)
			(layers "B.Cu" "B.Mask" "B.Paste")
			(net "P52V_HS_4287_S1N")
		)
		(pad "6" smd rect
			(at 3.400044 1.249934 270)
			(size 0.2794 0.762)
			(layers "B.Cu" "B.Mask" "B.Paste")
			(net "P52V_HS_4287_S1P")
		)
		(pad "7" smd rect
			(at 3.400044 1.75006 270)
			(size 0.2794 0.762)
			(layers "B.Cu" "B.Mask" "B.Paste")
			(net "P52V_HS_4287_ADC_P")
		)
		(pad "8" smd rect
			(at 3.400044 2.249932 270)
			(size 0.2794 0.762)
			(layers "B.Cu" "B.Mask" "B.Paste")
			(net "P52V_HS_4287_S2N")
		)
		(pad "9" smd rect
			(at 3.425444 2.750058 270)
			(size 0.2794 0.7112)
			(layers "B.Cu" "B.Mask" "B.Paste")
			(net "P52V_HS_4287_S2P")
		)
		(pad "10" smd rect
			(at 2.750058 3.425444 180)
			(size 0.2794 0.7112)
			(layers "B.Cu" "B.Mask" "B.Paste")
			(net "P52V_1")
		)
		(pad "11" smd rect
			(at 0.750062 3.400044 180)
			(size 0.2794 0.762)
			(layers "B.Cu" "B.Mask" "B.Paste")
			(net "P52V_HS1_UVLO_EN")
		)
		(pad "12" smd rect
			(at 0.249936 3.400044 180)
			(size 0.2794 0.762)
			(layers "B.Cu" "B.Mask" "B.Paste")
			(net "P52V_HS1_OV")
		)
		(pad "13" smd rect
			(at -0.249936 3.400044 180)
			(size 0.2794 0.762)
			(layers "B.Cu" "B.Mask" "B.Paste")
			(net "P52V_HS1_INTVCC")
		)
		(pad "14" smd rect
			(at -0.750062 3.400044 180)
			(size 0.2794 0.762)
			(layers "B.Cu" "B.Mask" "B.Paste")
			(net "GND_FIELD_SIGNAL")
		)
		(pad "15" smd rect
			(at -1.249934 3.400044 180)
			(size 0.2794 0.762)
			(layers "B.Cu" "B.Mask" "B.Paste")
			(net "P52V_HS1_DVCC")
		)
		(pad "16" smd rect
			(at -1.75006 3.400044 180)
			(size 0.2794 0.762)
			(layers "B.Cu" "B.Mask" "B.Paste")
			(net "P52V_HS1_ADR0")
		)
		(pad "17" smd rect
			(at -2.249932 3.400044 180)
			(size 0.2794 0.762)
			(layers "B.Cu" "B.Mask" "B.Paste")
			(net "P52V_HS1_ADR1")
		)
		(pad "18" smd rect
			(at -2.750058 3.425444 180)
			(size 0.2794 0.7112)
			(layers "B.Cu" "B.Mask" "B.Paste")
			(net "Net_401")
		)
		(pad "19" smd rect
			(at -3.425444 2.750058 270)
			(size 0.2794 0.7112)
			(layers "B.Cu" "B.Mask" "B.Paste")
			(net "P52V_HS1_MODE")
		)
		(pad "20" smd rect
			(at -3.400044 2.249932 270)
			(size 0.2794 0.762)
			(layers "B.Cu" "B.Mask" "B.Paste")
			(net "P52V_HS1_TMR")
		)
		(pad "21" smd rect
			(at -3.400044 1.75006 270)
			(size 0.2794 0.762)
			(layers "B.Cu" "B.Mask" "B.Paste")
			(net "P52V_HS1_CLKIN")
		)
		(pad "22" smd rect
			(at -3.400044 1.249934 270)
			(size 0.2794 0.762)
			(layers "B.Cu" "B.Mask" "B.Paste")
			(net "Net_405")
		)
		(pad "23" smd rect
			(at -3.400044 0.750062 270)
			(size 0.2794 0.762)
			(layers "B.Cu" "B.Mask" "B.Paste")
			(net "P52V_HS1_EN")
		)
		(pad "24" smd rect
			(at -3.400044 0.249936 270)
			(size 0.2794 0.762)
			(layers "B.Cu" "B.Mask" "B.Paste")
			(net "P52V_HS1_SIO")
		)
		(pad "25" smd rect
			(at -3.400044 -0.249936 270)
			(size 0.2794 0.762)
			(layers "B.Cu" "B.Mask" "B.Paste")
			(net "P52V_HS1_SCK")
		)
		(pad "26" smd rect
			(at -3.400044 -0.750062 270)
			(size 0.2794 0.762)
			(layers "B.Cu" "B.Mask" "B.Paste")
			(net "P52V_HS1_CS")
		)
		(pad "27" smd rect
			(at -3.400044 -1.249934 270)
			(size 0.2794 0.762)
			(layers "B.Cu" "B.Mask" "B.Paste")
			(net "SMB_P52V_PDB_SCL_R3")
		)
		(pad "28" smd rect
			(at -3.400044 -1.75006 270)
			(size 0.2794 0.762)
			(layers "B.Cu" "B.Mask" "B.Paste")
			(net "SMB_P52V_HS1_SDAI")
		)
		(pad "29" smd rect
			(at -3.400044 -2.249932 270)
			(size 0.2794 0.762)
			(layers "B.Cu" "B.Mask" "B.Paste")
			(net "SMB_P52V_HS1_SDAO")
		)
		(pad "30" smd rect
			(at -3.425444 -2.750058 270)
			(size 0.2794 0.7112)
			(layers "B.Cu" "B.Mask" "B.Paste")
			(net "Net_402")
		)
		(pad "31" smd rect
			(at -2.750058 -3.425444 180)
			(size 0.2794 0.7112)
			(layers "B.Cu" "B.Mask" "B.Paste")
			(net "Net_403")
		)
		(pad "32" smd rect
			(at -2.249932 -3.400044 180)
			(size 0.2794 0.762)
			(layers "B.Cu" "B.Mask" "B.Paste")
			(net "Net_404")
		)
		(pad "33" smd rect
			(at -1.75006 -3.400044 180)
			(size 0.2794 0.762)
			(layers "B.Cu" "B.Mask" "B.Paste")
			(net "GND_FIELD_SIGNAL")
		)
		(pad "34" smd rect
			(at -1.249934 -3.400044 180)
			(size 0.2794 0.762)
			(layers "B.Cu" "B.Mask" "B.Paste")
			(net "GND_FIELD_SIGNAL")
		)
		(pad "35" smd rect
			(at -0.750062 -3.400044 180)
			(size 0.2794 0.762)
			(layers "B.Cu" "B.Mask" "B.Paste")
			(net "P52V_HS1_TEMP")
		)
		(pad "36" smd rect
			(at -0.249936 -3.400044 180)
			(size 0.2794 0.762)
			(layers "B.Cu" "B.Mask" "B.Paste")
			(net "P52V_HS1_FLT")
		)
		(pad "37" smd rect
			(at 0.249936 -3.400044 180)
			(size 0.2794 0.762)
			(layers "B.Cu" "B.Mask" "B.Paste")
			(net "PWRGD_P52V_HS1_4287_PG_N")
		)
		(pad "38" smd rect
			(at 0.750062 -3.400044 180)
			(size 0.2794 0.762)
			(layers "B.Cu" "B.Mask" "B.Paste")
			(net "P52V_HS1_FB")
		)
		(pad "39" smd rect
			(at 2.750058 -3.425444 180)
			(size 0.2794 0.7112)
			(layers "B.Cu" "B.Mask" "B.Paste")
			(net "P52V_HS1_VDSFB")
		)
		(pad "40" smd circle
			(at -0.87503 0 180)
			(size 0 0)
			(layers "B.Cu" "B.Mask" "B.Paste")
			(net "GND_FIELD_SIGNAL")
		)
		(zone
			(layer "B.Cu")
			(hatch none 0.5)
			(connect_pads
				(clearance 0)
			)
			(min_thickness 0.25)
			(keepout
				(tracks not_allowed)
				(vias allowed)
				(pads allowed)
				(copperpour not_allowed)
				(footprints allowed)
			)
			(placement
				(enabled no)
				(sheetname "")
			)
			(fill
				(thermal_gap 0.5)
				(thermal_bridge_width 0.5)
				(island_removal_mode 0)
			)
			(polygon
				(pts
					(xy 296.490644 -72.54748) (xy 296.490644 -70.7644) (xy 294.5384 -70.7644) (xy 294.5384 -72.4916)
					(xy 294.1574 -72.8726) (xy 290.7538 -72.8726) (xy 290.7538 -67.3354) (xy 294.5384 -67.3354) (xy 294.5384 -70.739)
					(xy 296.490644 -70.739) (xy 296.490644 -67.65798) (xy 296.541444 -67.65798) (xy 296.541444 -67.084956)
					(xy 294.46982 -67.084956) (xy 294.46982 -67.135756) (xy 291.07638 -67.135756) (xy 291.07638 -67.084956)
					(xy 290.503356 -67.084956) (xy 290.503356 -67.65798) (xy 290.554156 -67.65798) (xy 290.554156 -72.55002)
					(xy 290.503356 -72.55002) (xy 290.503356 -73.123044) (xy 291.07638 -73.123044) (xy 291.07638 -73.072244)
					(xy 294.46982 -73.072244) (xy 294.46982 -73.123044) (xy 296.541444 -73.123044) (xy 296.541444 -72.54748)
				)
			)
		)
	)
	(footprint ""
		(layer "B.Cu")
		(at 260.6294 -53.975)
		(property "Reference" "R413"
			(at 0 0 0)
			(layer "B.SilkS")
			(hide yes)
			(effects
				(font
					(size 1.27 1.27)
				)
				(justify mirror)
			)
		)
		(property "Value" ""
			(at 0 0 0)
			(layer "B.Fab")
			(effects
				(font
					(size 1.27 1.27)
				)
				(justify mirror)
			)
		)
		(duplicate_pad_numbers_are_jumpers no)
		(fp_line
			(start -0.7874 -0.4064)
			(end -0.7874 0.4064)
			(stroke
				(width 0.1524)
				(type default)
			)
			(layer "B.SilkS")
		)
		(fp_line
			(start -0.7874 0.4064)
			(end 0.7874 0.4064)
			(stroke
				(width 0.1524)
				(type default)
			)
			(layer "B.SilkS")
		)
		(fp_line
			(start 0.7874 -0.4064)
			(end -0.7874 -0.4064)
			(stroke
				(width 0.1524)
				(type default)
			)
			(layer "B.SilkS")
		)
		(fp_line
			(start 0.7874 0.4064)
			(end 0.7874 -0.4064)
			(stroke
				(width 0.1524)
				(type default)
			)
			(layer "B.SilkS")
		)
		(fp_line
			(start -0.67945 -0.3048)
			(end -0.67945 0.3048)
			(stroke
				(width 0.1)
				(type default)
			)
			(layer "B.Fab")
		)
		(fp_line
			(start -0.67945 0.3048)
			(end -0.120396 0.3048)
			(stroke
				(width 0.1)
				(type default)
			)
			(layer "B.Fab")
		)
		(fp_line
			(start -0.12065 -0.3048)
			(end -0.67945 -0.3048)
			(stroke
				(width 0.1)
				(type default)
			)
			(layer "B.Fab")
		)
		(fp_line
			(start -0.12065 -0.2794)
			(end -0.12065 -0.3048)
			(stroke
				(width 0.1)
				(type default)
			)
			(layer "B.Fab")
		)
		(fp_line
			(start -0.120396 0.2794)
			(end 0.12065 0.2794)
			(stroke
				(width 0.1)
				(type default)
			)
			(layer "B.Fab")
		)
		(fp_line
			(start -0.120396 0.3048)
			(end -0.120396 0.2794)
			(stroke
				(width 0.1)
				(type default)
			)
			(layer "B.Fab")
		)
		(fp_line
			(start 0.12065 -0.305054)
			(end 0.12065 -0.2794)
			(stroke
				(width 0.1)
				(type default)
			)
			(layer "B.Fab")
		)
		(fp_line
			(start 0.12065 -0.2794)
			(end -0.12065 -0.2794)
			(stroke
				(width 0.1)
				(type default)
			)
			(layer "B.Fab")
		)
		(fp_line
			(start 0.12065 0.2794)
			(end 0.12065 0.3048)
			(stroke
				(width 0.1)
				(type default)
			)
			(layer "B.Fab")
		)
		(fp_line
			(start 0.12065 0.3048)
			(end 0.67945 0.3048)
			(stroke
				(width 0.1)
				(type default)
			)
			(layer "B.Fab")
		)
		(fp_line
			(start 0.67945 -0.305054)
			(end 0.12065 -0.305054)
			(stroke
				(width 0.1)
				(type default)
			)
			(layer "B.Fab")
		)
		(fp_line
			(start 0.67945 0.3048)
			(end 0.67945 -0.305054)
			(stroke
				(width 0.1)
				(type default)
			)
			(layer "B.Fab")
		)
		(pad "1" smd circle
			(at 0.40005 0 180)
			(size 0 0)
			(layers "B.Cu" "B.Mask" "B.Paste")
			(net "GPU_HSC1_BUF_EN")
		)
		(pad "2" smd circle
			(at -0.40005 0 180)
			(size 0 0)
			(layers "B.Cu" "B.Mask" "B.Paste")
			(net "FM_HS1_EN_FUSE")
		)
	)
)
